FILE_TYPE = MULTI_PHYS_TABLE;

PART '24LC16BT_I_ST_TSSOP8'
CLASS = IC 

{========================================================================================}
:'CLS_PN'             = 'JEDEC_TYPE'       |'ALT_SYMBOLS'        |'DESCRIPTION'                           ;
{========================================================================================}
 'G221-10174-01'      = 'SOP8_173X118_P0256'  |'(SOP8_173X118_P0256)'  |'IC,24LC16BT-I/ST,16KBITS,I2C EEPROM,2.5V-5.5V,-40C TO +85C,TSSOP8,ROHS'  
 'G221-10176-01'      = 'SOP8_173X118_P0256'  |'(SOP8_173X118_P0256)'  |'IC,24LC64T-I/ST,64KBITS,I2C EEPROM,2.5V-5.5V,-40C TO +85C,TSSOP8,ROHS'
 'G221-10242-01'      = 'SOP8_154_P050_V1'  |'(SOP8_154_P050_V1)'  |'IC,I2C,EEPROM,512K,SOIC8'
 
END_PART

END.


